# BASEBOARD_FAB2 (Tioga Pass) — schematic netlist excerpt (pin names and nets, part order shuffled) for the footprints in the layout excerpt that follows; sources: Cadence DE-HDL packaged netlist, KiCad conversion of Wiwynn_Tioga_Pass_MB.brd

C6N5  CAPP  68UF 16V 20% TANT  pkg 3018  page 195 : A = P12V_STBY ; B = GND
C5P12  CAP  100UF 4V 20% X5R  pkg 0805  page 42 : A = PVCCMCP_CPU0 ; B = GND
R9R2  RES  0.0 5% CHIP  pkg 0402  page 207 : A = VR_PVCCIN_CPU1_PH1_VCIN ; B = P5V_STBY

(kicad_pcb
	(version 20260206)
	(generator "pcbnew")
	(generator_version "10.0")
	(general
		(thickness 1.6)
		(legacy_teardrops no)
	)
	(paper "A4")
	(title_block
		(title "Wiwynn_Tioga_Pass_MB.brd")
		(comment 1 "Tioga Pass / footprints 3352-3354 of 4770")
	)
	(layers
		(0 "F.Cu" signal "TOP")
		(4 "In1.Cu" signal "L2GND")
		(6 "In2.Cu" signal "L3")
		(8 "In3.Cu" signal "L4GND")
		(10 "In4.Cu" signal "L5")
		(12 "In5.Cu" signal "L6GND")
		(14 "In6.Cu" signal "L7VCC")
		(16 "In7.Cu" signal "L8VCC")
		(18 "In8.Cu" signal "L9GND")
		(20 "In9.Cu" signal "L10")
		(22 "In10.Cu" signal "L11GND")
		(24 "In11.Cu" signal "L12")
		(26 "In12.Cu" signal "L13GND")
		(2 "B.Cu" signal "BOTTOM")
		(9 "F.Adhes" user "F.Adhesive")
		(11 "B.Adhes" user "B.Adhesive")
		(13 "F.Paste" user "Package Geometry/Pastemask Top")
		(15 "B.Paste" user "Package Geometry/Pastemask Bottom")
		(5 "F.SilkS" user "Ref Des/Silkscreen Top")
		(7 "B.SilkS" user "Ref Des/Silkscreen Bottom")
		(1 "F.Mask" user "Board Geometry/Soldermask Top")
		(3 "B.Mask" user "Board Geometry/Soldermask Bottom")
		(17 "Dwgs.User" user "User.Drawings")
		(19 "Cmts.User" user "User.Comments")
		(21 "Eco1.User" user "User.Eco1")
		(23 "Eco2.User" user "User.Eco2")
		(25 "Edge.Cuts" user "Board Geometry/Outline")
		(27 "Margin" user)
		(31 "F.CrtYd" user "Package Geometry/Place Bound Top")
		(29 "B.CrtYd" user "Package Geometry/Place Bound Bottom")
		(35 "F.Fab" user "Ref Des/Assembly Top")
		(33 "B.Fab" user "Ref Des/Assembly Bottom")
	)
	(footprint ""
		(layer "B.Cu")
		(at 271.731486 -79.60614 180)
		(property "Reference" "C5P12"
			(at 0 0 0)
			(layer "B.SilkS")
			(hide yes)
			(effects
				(font
					(size 1.27 1.27)
				)
				(justify mirror)
			)
		)
		(property "Value" ""
			(at 0 0 0)
			(layer "B.Fab")
			(effects
				(font
					(size 1.27 1.27)
				)
				(justify mirror)
			)
		)
		(duplicate_pad_numbers_are_jumpers no)
		(fp_poly
			(pts
				(xy 0.7239 -0.2159) (xy -0.7239 -0.2159) (xy -0.7239 1.9939) (xy 0.7239 1.9939)
			)
			(stroke
				(width 0)
				(type default)
			)
			(fill no)
			(layer "B.CrtYd")
		)
		(fp_line
			(start 0.7239 1.9939)
			(end -0.7239 1.9939)
			(stroke
				(width 0.1)
				(type default)
			)
			(layer "B.Fab")
		)
		(fp_line
			(start 0.7239 -0.2159)
			(end 0.7239 1.9939)
			(stroke
				(width 0.1)
				(type default)
			)
			(layer "B.Fab")
		)
		(fp_line
			(start -0.7239 1.9939)
			(end -0.7239 -0.2159)
			(stroke
				(width 0.1)
				(type default)
			)
			(layer "B.Fab")
		)
		(fp_line
			(start -0.7239 -0.2159)
			(end 0.7239 -0.2159)
			(stroke
				(width 0.1)
				(type default)
			)
			(layer "B.Fab")
		)
		(pad "1" smd rect
			(at 0 0)
			(size 1.27 1.016)
			(layers "B.Cu" "B.Mask" "B.Paste")
			(net "PVCCMCP_CPU0")
		)
		(pad "2" smd rect
			(at 0 1.778)
			(size 1.27 1.016)
			(layers "B.Cu" "B.Mask" "B.Paste")
			(net "GND")
		)
		(zone
			(layer "B.Cu")
			(hatch none 0.5)
			(connect_pads
				(clearance 0)
			)
			(min_thickness 0.25)
			(keepout
				(tracks not_allowed)
				(vias allowed)
				(pads allowed)
				(copperpour not_allowed)
				(footprints allowed)
			)
			(placement
				(enabled no)
				(sheetname "")
			)
			(fill
				(thermal_gap 0.5)
				(thermal_bridge_width 0.5)
				(island_removal_mode 0)
			)
			(polygon
				(pts
					(xy 271.096486 -80.11414) (xy 272.366486 -80.11414) (xy 272.366486 -80.87614) (xy 271.096486 -80.87614)
				)
			)
		)
	)
	(footprint ""
		(layer "B.Cu")
		(at 32.3342 -54.5084 90)
		(property "Reference" "R9R2"
			(at 0 0 90)
			(layer "B.SilkS")
			(hide yes)
			(effects
				(font
					(size 1.27 1.27)
				)
				(justify mirror)
			)
		)
		(property "Value" ""
			(at 0 0 90)
			(layer "B.Fab")
			(effects
				(font
					(size 1.27 1.27)
				)
				(justify mirror)
			)
		)
		(duplicate_pad_numbers_are_jumpers no)
		(fp_poly
			(pts
				(xy 0.2794 -0.1016) (xy -0.2794 -0.1016) (xy -0.2794 0.9906) (xy 0.2794 0.9906)
			)
			(stroke
				(width 0)
				(type default)
			)
			(fill no)
			(layer "B.CrtYd")
		)
		(fp_line
			(start 0.2794 -0.1016)
			(end 0.2794 0.9906)
			(stroke
				(width 0.1)
				(type default)
			)
			(layer "B.Fab")
		)
		(fp_line
			(start -0.2794 -0.1016)
			(end 0.2794 -0.1016)
			(stroke
				(width 0.1)
				(type default)
			)
			(layer "B.Fab")
		)
		(fp_line
			(start 0.2794 0.9906)
			(end -0.2794 0.9906)
			(stroke
				(width 0.1)
				(type default)
			)
			(layer "B.Fab")
		)
		(fp_line
			(start -0.2794 0.9906)
			(end -0.2794 -0.1016)
			(stroke
				(width 0.1)
				(type default)
			)
			(layer "B.Fab")
		)
		(pad "1" smd rect
			(at 0 0 270)
			(size 0.508 0.508)
			(layers "B.Cu" "B.Mask" "B.Paste")
			(net "VR_PVCCIN_CPU1_PH1_VCIN")
		)
		(pad "2" smd rect
			(at 0 0.889 270)
			(size 0.508 0.508)
			(layers "B.Cu" "B.Mask" "B.Paste")
			(net "P5V_STBY")
		)
		(zone
			(layer "B.Cu")
			(hatch none 0.5)
			(connect_pads
				(clearance 0)
			)
			(min_thickness 0.25)
			(keepout
				(tracks allowed)
				(vias not_allowed)
				(pads allowed)
				(copperpour not_allowed)
				(footprints allowed)
			)
			(placement
				(enabled no)
				(sheetname "")
			)
			(fill
				(thermal_gap 0.5)
				(thermal_bridge_width 0.5)
				(island_removal_mode 0)
			)
			(polygon
				(pts
					(xy 32.5882 -54.7624) (xy 32.5882 -54.2544) (xy 32.9692 -54.2544) (xy 32.9692 -54.7624)
				)
			)
		)
		(zone
			(layer "B.Cu")
			(hatch none 0.5)
			(connect_pads
				(clearance 0)
			)
			(min_thickness 0.25)
			(keepout
				(tracks not_allowed)
				(vias allowed)
				(pads allowed)
				(copperpour not_allowed)
				(footprints allowed)
			)
			(placement
				(enabled no)
				(sheetname "")
			)
			(fill
				(thermal_gap 0.5)
				(thermal_bridge_width 0.5)
				(island_removal_mode 0)
			)
			(polygon
				(pts
					(xy 32.9692 -54.7624) (xy 32.9692 -54.2544) (xy 32.5882 -54.2544) (xy 32.5882 -54.7624)
				)
			)
		)
	)
	(footprint ""
		(layer "B.Cu")
		(at 179.2986 -95.4532)
		(property "Reference" "C6N5"
			(at 3.17373 4.6482 270)
			(unlocked yes)
			(layer "B.SilkS")
			(effects
				(font
					(size 0.7874 0.5842)
					(thickness 0.1524)
				)
				(justify mirror)
			)
		)
		(property "Value" ""
			(at 0 0 0)
			(layer "B.Fab")
			(effects
				(font
					(size 1.27 1.27)
				)
				(justify mirror)
			)
		)
		(duplicate_pad_numbers_are_jumpers no)
		(fp_line
			(start -2.504948 -1.616456)
			(end -2.504948 1.633728)
			(stroke
				(width 0.1524)
				(type default)
			)
			(layer "B.SilkS")
		)
		(fp_line
			(start -2.504948 1.633728)
			(end -1.6002 1.633728)
			(stroke
				(width 0.1524)
				(type default)
			)
			(layer "B.SilkS")
		)
		(fp_line
			(start -2.286 7.366)
			(end -2.286 1.63195)
			(stroke
				(width 0.1524)
				(type default)
			)
			(layer "B.SilkS")
		)
		(fp_line
			(start -2.286 7.366)
			(end -1.600708 7.366)
			(stroke
				(width 0.1524)
				(type default)
			)
			(layer "B.SilkS")
		)
		(fp_line
			(start -1.6002 -1.616456)
			(end -2.504948 -1.616456)
			(stroke
				(width 0.1524)
				(type default)
			)
			(layer "B.SilkS")
		)
		(fp_line
			(start 1.6002 -1.616456)
			(end 2.563114 -1.616456)
			(stroke
				(width 0.1524)
				(type default)
			)
			(layer "B.SilkS")
		)
		(fp_line
			(start 2.286 7.366)
			(end 1.60147 7.366)
			(stroke
				(width 0.1524)
				(type default)
			)
			(layer "B.SilkS")
		)
		(fp_line
			(start 2.286 7.366)
			(end 2.286 1.632712)
			(stroke
				(width 0.1524)
				(type default)
			)
			(layer "B.SilkS")
		)
		(fp_line
			(start 2.563114 -1.616456)
			(end 2.563114 1.633728)
			(stroke
				(width 0.1524)
				(type default)
			)
			(layer "B.SilkS")
		)
		(fp_line
			(start 2.563114 1.633728)
			(end 1.6002 1.633728)
			(stroke
				(width 0.1524)
				(type default)
			)
			(layer "B.SilkS")
		)
		(fp_rect
			(start 2.286 7.366)
			(end -2.286 -0.254)
			(stroke
				(width 0)
				(type default)
			)
			(fill no)
			(layer "B.CrtYd")
		)
		(fp_line
			(start -2.286 -0.254)
			(end -2.286 7.366)
			(stroke
				(width 0.1)
				(type default)
			)
			(layer "B.Fab")
		)
		(fp_line
			(start -2.286 7.366)
			(end 2.286 7.366)
			(stroke
				(width 0.1)
				(type default)
			)
			(layer "B.Fab")
		)
		(fp_line
			(start 2.286 -0.254)
			(end -2.286 -0.254)
			(stroke
				(width 0.1)
				(type default)
			)
			(layer "B.Fab")
		)
		(fp_line
			(start 2.286 7.366)
			(end 2.286 -0.254)
			(stroke
				(width 0.1)
				(type default)
			)
			(layer "B.Fab")
		)
		(pad "1" smd rect
			(at 0 0 180)
			(size 2.54 3.048)
			(layers "B.Cu" "B.Mask" "B.Paste")
			(net "P12V_STBY")
		)
		(pad "2" smd rect
			(at 0 7.112 180)
			(size 2.54 3.048)
			(layers "B.Cu" "B.Mask" "B.Paste")
			(net "GND")
		)
	)
)
